FILE_TYPE=LIBRARY_PARTS;
primitive '4K42R2F-GP_SMD-RG';
  pin
    '1':
      PIN_NUMBER='(1)';
      PIN_TYPE='ANALOG';
      NO_LOAD_CHECK='Both';
      NO_IO_CHECK='Both';
      NO_ASSERT_CHECK='TRUE';
      NO_DIR_CHECK='TRUE';
      ALLOW_CONNECT='TRUE';
    '2':
      PIN_NUMBER='(2)';
      PIN_TYPE='ANALOG';
      NO_LOAD_CHECK='Both';
      NO_IO_CHECK='Both';
      NO_ASSERT_CHECK='TRUE';
      NO_DIR_CHECK='TRUE';
      ALLOW_CONNECT='TRUE';
  end_pin;
  body
    PART_NAME='4K42R2F-GP';
    BODY_NAME='4K42R2F-GP';
    PHYS_DES_PREFIX='R';
    CLASS='DISCRETE';
  end_body;
end_primitive;

END.
